M48
INCH,TZ
T01C.01
T02C.012
T03C.04
T04C.044
T05C.063
T06C.065
T07C.086
T08C.14
;EXTENTS: -10.000 -20.000 65.000  20.000  
;LEADER: 12 
;HEADER: 
;CODE  : ASCII 
;FILE  : 15750-1.rou for board 15750-1.brd
%
G90
F1
M16
G40
M30
